5
5
4
4
3
3
2
2
1
1
D D
C C
B B
A A
Tray Backplane 
Version: 2012/10/23 
PCB: DA0T6MTH8C0 
LAYER: 8 LAYERS 
Title 
Size Document Number Rev
Date: Sheet 
of 
Cover 1A
Tray Backplane Assembly V1 
Cloud Server Infrastructure Engineering
C
1 11Monday, January 27, 2014 
Title 
Size Document Number Rev
Date: Sheet 
of 
Cover 1A
Tray Backplane Assembly V1 
Cloud Server Infrastructure Engineering
C
1 11Monday, January 27, 2014 
Title 
Size Document Number Rev
Date: Sheet 
of 
Cover 1A
Tray Backplane Assembly V1 
Cloud Server Infrastructure Engineering
C
1 11Monday, January 27, 2014 



5
5
4
4
3
3
2
2
1
1
D D
C C
B B
A A
Title 
Size Document Number Rev
Date: Sheet 
of 
Block Diagram 1A
Tray Backplane Assembly V1 
Cloud Server Infrastructure Engineering
C
2 11Monday, January 27, 2014 
Title 
Size Document Number Rev
Date: Sheet 
of 
Block Diagram 1A
Tray Backplane Assembly V1 
Cloud Server Infrastructure Engineering
C
2 11Monday, January 27, 2014 
Title 
Size Document Number Rev
Date: Sheet 
of 
Block Diagram 1A
Tray Backplane Assembly V1 
Cloud Server Infrastructure Engineering
C
2 11Monday, January 27, 2014 



5
5
4
4
3
3
2
2
1
1
D D
C C
B B
A A
Title 
Size Document Number Rev
Date: Sheet 
of 
Stackup 1A
Tray Backplane Assembly V1 
Cloud Server Infrastructure Engineering
C
3 11Monday, January 27, 2014 
Title 
Size Document Number Rev
Date: Sheet 
of 
Stackup 1A
Tray Backplane Assembly V1 
Cloud Server Infrastructure Engineering
C
3 11Monday, January 27, 2014 
Title 
Size Document Number Rev
Date: Sheet 
of 
Stackup 1A
Tray Backplane Assembly V1 
Cloud Server Infrastructure Engineering
C
3 11Monday, January 27, 2014 



5
5
4
4
3
3
2
2
1
1
D D
C C
B B
A A
Title 
Size Document Number Rev
Date: Sheet 
of 
Blank 1A
Tray Backplane Assembly V1 
Cloud Server Infrastructure Engineering
C
4 11Monday, January 27, 2014 
Title 
Size Document Number Rev
Date: Sheet 
of 
Blank 1A
Tray Backplane Assembly V1 
Cloud Server Infrastructure Engineering
C
4 11Monday, January 27, 2014 
Title 
Size Document Number Rev
Date: Sheet 
of 
Blank 1A
Tray Backplane Assembly V1 
Cloud Server Infrastructure Engineering
C
4 11Monday, January 27, 2014 



5
5
4
4
3
3
2
2
1
1
D D
C C
B B
A A
AIRMAX CONNECTOR - BLADE1 
LAN SIGNAL SAS SIGNAL 
GUIDE PIN SKU1  SKU2  TYPE 
 0     0     10G 
 0     1     SAS 6G 
 1     0     RESERVED 
 1     1     RESERVED 
CHECK WITH MOTHER BOARD POWER PIN DEFINE 
BLADE1_MATED_N 
SKU_PIN_BLAD1_1 
SKU_PIN_BLAD1_2 
BLADE1_MATED_N 
SFP1_PRESENT_N 
SFP2_PRESENT_N 
AIRMAX_RSVD1 
AIRMAX_RSVD2 
AIRMAX_RSVD3 
AIRMAX_RSVD4 
SFP1_PRESENT_N 
SFP2_PRESENT_N 
NODE2_EN 
NODE1_EN 
ENET10G_1_RDP (8) 
ENET10G_1_RDN (8) 
ENET1G_1_MDI0N (7) 
ENET1G_1_MDI0P (7) 
ENET10G_1_TDN (8) 
ENET10G_1_TDP (8) 
ENET1G_1_MDI2P (7) 
ENET1G_1_MDI2N (7) 
ENET1G_1_MDI1P (7) 
ENET1G_1_MDI1N (7) 
NODE1_EN (10) 
ENET1G_1_MDI3P (7) 
ENET1G_1_MDI3N (7) 
ENET10G_1_SDA (8) 
ENET10G_1_SCL (8) 
SKU_PIN_BLAD1_1 
NODE1_TXD (10) 
NODE1_RXD (10) 
ENET1G_2_MDI0N (7) 
ENET1G_2_MDI0P (7) 
ENET10G_2_SDA (8) 
ENET10G_2_SCL (8) 
NODE2_TXD (10) 
NODE2_RXD (10) 
SKU_PIN_BLAD1_2 
ENET1G_2_MDI1N (7) 
ENET1G_2_MDI1P (7) 
ENET1G_2_MDI2N (7) 
ENET1G_2_MDI2P (7) 
NODE2_EN (10) 
ENET1G_2_MDI3N (7) 
ENET1G_2_MDI3P (7) 
ENET10G_2_TDP (8) 
ENET10G_2_TDN (8) 
ENET10G_2_RDN (8) 
ENET10G_2_RDP (8) 
ENET10G_1_MOD_DEF0 (8) 
ENET10G_1_LOS (8) 
ENET10G_2_MOD_DEF0 (8) 
ENET10G_2_LOS (8) 
SAS_BLAD1_TX5_P (7) 
SAS_BLAD1_TX5_N (7) 
SAS_BLAD1_RX5_P (7) 
SAS_BLAD1_RX5_N (7) 
SAS_BLAD1_RX1_P (7) 
SAS_BLAD1_RX1_N (7) 
SAS_BLAD1_TX6_P (7) 
SAS_BLAD1_TX6_N (7) 
SAS_BLAD1_RX6_P (7) 
SAS_BLAD1_RX6_N (7) 
SAS_BLAD1_RX2_P (7) 
SAS_BLAD1_RX2_N (7) 
SAS_BLAD1_RX4_P (7) 
SAS_BLAD1_RX4_N (7) 
SAS_BLAD1_RX3_P (7) 
SAS_BLAD1_RX3_N (7) 
SAS_BLAD1_TX8_P (7) 
SAS_BLAD1_TX8_N (7) 
SAS_BLAD1_TX4_P (7) 
SAS_BLAD1_TX4_N (7) 
SAS_BLAD1_TX7_P (7) 
SAS_BLAD1_TX7_N (7) 
SAS_BLAD1_TX3_P (7) 
SAS_BLAD1_TX3_N (7) 
SAS_BLAD1_RX8_P (7) 
SAS_BLAD1_RX8_N (7) 
SAS_BLAD1_RX7_P (7) 
SAS_BLAD1_RX7_N (7) 
SAS_BLAD1_TX2_P (7) 
SAS_BLAD1_TX2_N (7) 
SAS_BLAD1_TX1_P (7) 
SAS_BLAD1_TX1_N (7) 
P12V 
P12V 
P3V3_BLAD1 
P3V3_BLAD1 
P12V 
P12V 
Title 
Size Document Number Rev
Date: Sheet 
of 
Airmax Connector 1 1A
Tray Backplane Assembly V1 
Cloud Server Infrastructure Engineering
C
5 11Monday, January 27, 2014 
Title 
Size Document Number Rev
Date: Sheet 
of 
Airmax Connector 1 1A
Tray Backplane Assembly V1 
Cloud Server Infrastructure Engineering
C
5 11Monday, January 27, 2014 
Title 
Size Document Number Rev
Date: Sheet 
of 
Airmax Connector 1 1A
Tray Backplane Assembly V1 
Cloud Server Infrastructure Engineering
C
5 11Monday, January 27, 2014 
R58 
100 
R0402 
5% 
NI 
JP4 
HEADER 1X2 
NI 
1
2
R34 100 
R0402 5% 
R66 0
C1 
1UF 
25V 
C0603 
J6 
CONN3_10044366101LF 
11
22
33
R56 
100 
R0402 
5% 
J3 
CONN24_100526204555P00LF 
B1 B1 
B2 B2 
B3 B3 
B4 B4 
B5 B5 
B6 B6 
A1 A1 
A2 A2 
A3 A3 
A4 A4 
A5 A5 
A6 A6 
D1 D1 
D2 D2 
D3 D3 
D4 D4 
D5 D5 
D6 D6 
C1 C1 
C2 C2 
C3 C3 
C4 C4 
C5 C5 
C6 C6 
R69 0 C3 
0.1UF 
25V 
C0402 
J5 
CONN3_10044366101LF 
11
22
33
C2 
1UF 
25V 
C0603 
R85 3.3K 
5% R0402 
NI 
R84 10K 
5% R0402 
NI 
JP3 
HEADER 1X2 
NI 
1
2
R87 3.3K 
5% R0402 
NI 
C4 
0.1UF 
25V 
C0402 R59 
100 
R0402 
5% 
NI 
R39 
10K 
5% 
R0402 
NI 
R86 10K 
5% R0402 
NI 
R68 0NI 
A B C D E F G H I
01 
02 
03 
04 
05 
06 
J25 
CONN54_10053656101LF 
A6 A6 
B6 B6 
C6 C6 
D6 D6 
E6 E6 
F6 F6 
G6 G6 
H6 H6 
I6 I6 
A5 A5 
B5 B5 
C5 C5 
D5 D5 
E5 E5 
F5 F5 
G5 G5 
H5 H5 
I5 I5 
A4 A4 
B4 B4 
C4 C4 
D4 D4 
E4 E4 
F4 F4 
G4 G4 
H4 H4 
I4 I4 
A3 A3 
B3 B3 
C3 C3 
D3 D3 
E3 E3 
F3 F3 
G3 G3 
H3 H3 
I3 I3 
A2 A2 
B2 B2 
C2 C2 
D2 D2 
E2 E2 
F2 F2 
G2 G2 
H2 H2 
I2 I2 
A1 A1 
B1 B1 
C1 C1 
D1 D1 
E1 E1 
F1 F1 
G1 G1 
H1 H1 
I1 I1 
R38 
100 
R0402 
5% 
A B C D E F G H I
01 
02 
03 
04 
05 
06 
J24 
CONN54_10053656101LF 
A6 A6 
B6 B6 
C6 C6 
D6 D6 
E6 E6 
F6 F6 
G6 G6 
H6 H6 
I6 I6 
A5 A5 
B5 B5 
C5 C5 
D5 D5 
E5 E5 
F5 F5 
G5 G5 
H5 H5 
I5 I5 
A4 A4 
B4 B4 
C4 C4 
D4 D4 
E4 E4 
F4 F4 
G4 G4 
H4 H4 
I4 I4 
A3 A3 
B3 B3 
C3 C3 
D3 D3 
E3 E3 
F3 F3 
G3 G3 
H3 H3 
I3 I3 
A2 A2 
B2 B2 
C2 C2 
D2 D2 
E2 E2 
F2 F2 
G2 G2 
H2 H2 
I2 I2 
A1 A1 
B1 B1 
C1 C1 
D1 D1 
E1 E1 
F1 F1 
G1 G1 
H1 H1 
I1 I1 
R57 
10K 
5% 
R0402 
NI 
R67 0NI 



5
5
4
4
3
3
2
2
1
1
D D
C C
B B
A A
GUIDE PIN 
AIRMAX CONNECTOR - BLADE2 
LAN SIGNAL SAS SIGNAL 
SKU1  SKU2  TYPE 
 0     0     10G 
 0     1     SAS 6G 
 1     0     RESERVED 
 1     1     RESERVED 
SKU_PIN_BLAD2_1 
SKU_PIN_BLAD2_2 
SFP4_PRESENT_N 
AIRMAX_RSVD5 
AIRMAX_RSVD6 
AIRMAX_RSVD7 
AIRMAX_RSVD8 
SFP3_PRESENT_N 
BLADE2_MATED_N 
SFP3_PRESENT_N 
SFP4_PRESENT_N 
BLADE2_MATED_N 
NODE4_EN 
NODE3_EN 
ENET10G_3_RDP (9) 
SAS_BLAD2_TX5_P (7) 
SAS_BLAD2_TX5_N (7) 
SAS_BLAD2_RX5_P (7) 
SAS_BLAD2_RX5_N (7) 
SAS_BLAD2_RX1_P (7) 
SAS_BLAD2_RX1_N (7) 
SAS_BLAD2_TX6_P (7) 
SAS_BLAD2_TX6_N (7) 
SAS_BLAD2_RX6_P (7) 
SAS_BLAD2_RX6_N (7) 
SAS_BLAD2_RX2_P (7) 
SAS_BLAD2_RX2_N (7) 
SKU_PIN_BLAD2_1 
ENET1G_4_MDI3N (7) 
ENET1G_4_MDI3P (7) 
ENET10G_3_RDN (9) 
SAS_BLAD2_RX4_P (7) 
SAS_BLAD2_RX4_N (7) 
SAS_BLAD2_RX3_P (7) 
SAS_BLAD2_RX3_N (7) 
SAS_BLAD2_TX8_P (7) 
SAS_BLAD2_TX8_N (7) 
SAS_BLAD2_TX4_P (7) 
SAS_BLAD2_TX4_N (7) 
SAS_BLAD2_TX7_P (7) 
SAS_BLAD2_TX7_N (7) 
SAS_BLAD2_TX3_P (7) 
SAS_BLAD2_TX3_N (7) 
NODE3_TXD (10) 
NODE3_RXD (10) 
ENET10G_4_SDA (9) 
ENET10G_4_SCL (9) 
ENET1G_3_MDI0N (7) 
ENET1G_3_MDI0P (7) 
ENET10G_4_TDP (9) 
ENET10G_4_TDN (9) 
ENET10G_4_RDN (9) 
ENET10G_4_RDP (9) 
NODE4_TXD (10) 
NODE4_RXD (10) 
ENET10G_3_TDN (9) 
ENET10G_3_TDP (9) 
SKU_PIN_BLAD2_2 
ENET1G_4_MDI1N (7) 
ENET1G_4_MDI1P (7) 
ENET1G_4_MDI2N (7) 
ENET1G_4_MDI2P (7) 
ENET1G_3_MDI2P (7) 
ENET1G_3_MDI2N (7) 
ENET1G_3_MDI3P (7) 
ENET1G_3_MDI3N (7) 
ENET1G_3_MDI1P (7) 
ENET1G_3_MDI1N (7) 
NODE3_EN (10) 
NODE4_EN (10) 
ENET10G_3_SDA (9) 
ENET10G_3_SCL (9) 
ENET1G_4_MDI0N (7) 
ENET1G_4_MDI0P (7) 
ENET10G_3_MOD_DEF0 (9) 
ENET10G_3_LOS (9) 
ENET10G_4_MOD_DEF0 (9) 
ENET10G_4_LOS (9) 
SAS_BLAD2_RX7_P (7) 
SAS_BLAD2_RX7_N (7) 
SAS_BLAD2_RX8_P (7) 
SAS_BLAD2_RX8_N (7) 
SAS_BLAD2_TX1_P (7) 
SAS_BLAD2_TX1_N (7) 
SAS_BLAD2_TX2_P (7) 
SAS_BLAD2_TX2_N (7) 
P12V 
P12V 
P3V3_BLAD2 
P3V3_BLAD2 
P12V 
P12V 
Title 
Size Document Number Rev
Date: Sheet 
of 
Airmax Connector 2 1A
Tray Backplane Assembly V1 
Cloud Server Infrastructure Engineering
C
6 11Monday, January 27, 2014 
Title 
Size Document Number Rev
Date: Sheet 
of 
Airmax Connector 2 1A
Tray Backplane Assembly V1 
Cloud Server Infrastructure Engineering
C
6 11Monday, January 27, 2014 
Title 
Size Document Number Rev
Date: Sheet 
of 
Airmax Connector 2 1A
Tray Backplane Assembly V1 
Cloud Server Infrastructure Engineering
C
6 11Monday, January 27, 2014 
C9 
1UF 
25V 
C0603 
R73 0
C11 
0.1UF 
25V 
C0402 
J11 
CONN3_10044366101LF 
11
22
33
J12 
CONN3_10044366101LF 
11
22
33
R61 
10K 
5% 
R0402 
JP8 
HEADER 1X2 
NI 
1
2
A B C D E F G H I
01 
02 
03 
04 
05 
06 
J7 
CONN54_10053656101LF 
A6 A6 
B6 B6 
C6 C6 
D6 D6 
E6 E6 
F6 F6 
G6 G6 
H6 H6 
I6 I6 
A5 A5 
B5 B5 
C5 C5 
D5 D5 
E5 E5 
F5 F5 
G5 G5 
H5 H5 
I5 I5 
A4 A4 
B4 B4 
C4 C4 
D4 D4 
E4 E4 
F4 F4 
G4 G4 
H4 H4 
I4 I4 
A3 A3 
B3 B3 
C3 C3 
D3 D3 
E3 E3 
F3 F3 
G3 G3 
H3 H3 
I3 I3 
A2 A2 
B2 B2 
C2 C2 
D2 D2 
E2 E2 
F2 F2 
G2 G2 
H2 H2 
I2 I2 
A1 A1 
B1 B1 
C1 C1 
D1 D1 
E1 E1 
F1 F1 
G1 G1 
H1 H1 
I1 I1 
R75 0
R91 3.3K 
5% R0402 
NI 
A B C D E F G H I
01 
02 
03 
04 
05 
06 
J8 
CONN54_10053656101LF 
A6 A6 
B6 B6 
C6 C6 
D6 D6 
E6 E6 
F6 F6 
G6 G6 
H6 H6 
I6 I6 
A5 A5 
B5 B5 
C5 C5 
D5 D5 
E5 E5 
F5 F5 
G5 G5 
H5 H5 
I5 I5 
A4 A4 
B4 B4 
C4 C4 
D4 D4 
E4 E4 
F4 F4 
G4 G4 
H4 H4 
I4 I4 
A3 A3 
B3 B3 
C3 C3 
D3 D3 
E3 E3 
F3 F3 
G3 G3 
H3 H3 
I3 I3 
A2 A2 
B2 B2 
C2 C2 
D2 D2 
E2 E2 
F2 F2 
G2 G2 
H2 H2 
I2 I2 
A1 A1 
B1 B1 
C1 C1 
D1 D1 
E1 E1 
F1 F1 
G1 G1 
H1 H1 
I1 I1 
R90 10K 
5% R0402 
NI 
R70 0NI 
R88 10K 
5% R0402 
NI 
R89 3.3K 
5% R0402 
NI 
JP7 
HEADER 1X2 
NI 
1
2
R72 0NI 
C12 
0.1UF 
25V 
C0402 
R64 
100 
R0402 
5% 
R60 
100 
R0402 
5% 
NI 
C10 
1UF 
25V 
C0603 
J9 
CONN24_100526204555P00LF 
B1 B1 
B2 B2 
B3 B3 
B4 B4 
B5 B5 
B6 B6 
A1 A1 
A2 A2 
A3 A3 
A4 A4 
A5 A5 
A6 A6 
D1 D1 
D2 D2 
D3 D3 
D4 D4 
D5 D5 
D6 D6 
C1 C1 
C2 C2 
C3 C3 
C4 C4 
C5 C5 
C6 C6 
R65 
10K 
5% 
R0402 
NI 
R71 
100 
R0402 
5% 
NI 
R36 100 
R0402 5% 
R74 
100 
R0402 
5% 
NI 



5
5
4
4
3
3
2
2
1
1
D D
C C
B B
A A
MINI SAS CAGE MINI SAS CAGE 
LAN SIGNAL 
IO CONNECTOR - BLADE1 
LAN SIGNAL 
SAS SIGNAL SAS SIGNAL 
ENET1G_1_MDI0P (5) 
ENET1G_1_MDI0N (5) 
ENET1G_1_MDI1P (5) 
ENET1G_2_MDI0N (5) 
ENET1G_2_MDI0P (5) 
ENET1G_2_MDI3N (5) 
ENET1G_2_MDI3P (5) 
ENET1G_2_MDI1P (5) 
ENET1G_3_MDI0P (6) 
ENET1G_3_MDI0N (6) 
ENET1G_3_MDI1P (6) 
ENET1G_3_MDI3P (6) 
ENET1G_3_MDI3N (6) 
ENET1G_4_MDI0N (6) 
ENET1G_4_MDI0P (6) 
ENET1G_4_MDI3N (6) 
ENET1G_4_MDI3P (6) 
ENET1G_4_MDI1P (6) 
SAS_BLAD1_RX1_P (5) 
SAS_BLAD1_RX1_N (5) 
SAS_BLAD1_TX1_P (5) 
SAS_BLAD1_TX1_N (5) 
SAS_BLAD1_TX2_P (5) 
SAS_BLAD1_TX2_N (5) 
SAS_BLAD1_TX4_P (5) 
SAS_BLAD1_TX4_N (5) 
SAS_BLAD1_TX3_P (5) 
SAS_BLAD1_TX3_N (5) 
SAS_BLAD1_RX2_P (5) 
SAS_BLAD1_RX2_N (5) 
SAS_BLAD1_RX3_P (5) 
SAS_BLAD1_RX3_N (5) 
SAS_BLAD1_RX4_P (5) 
SAS_BLAD1_RX4_N (5) 
SAS_BLAD1_TX6_P (5) 
SAS_BLAD1_TX6_N (5) 
SAS_BLAD1_TX8_P (5) 
SAS_BLAD1_TX8_N (5) 
SAS_BLAD1_TX7_P (5) 
SAS_BLAD1_TX7_N (5) 
SAS_BLAD1_RX5_P (5) 
SAS_BLAD1_RX5_N (5) 
SAS_BLAD1_TX5_P (5) 
SAS_BLAD1_TX5_N (5) 
SAS_BLAD1_RX6_P (5) 
SAS_BLAD1_RX6_N (5) 
SAS_BLAD1_RX7_P (5) 
SAS_BLAD1_RX7_N (5) 
SAS_BLAD1_RX8_P (5) 
SAS_BLAD1_RX8_N (5) 
SAS_BLAD2_TX2_P (6) 
SAS_BLAD2_TX2_N (6) 
SAS_BLAD2_TX4_P (6) 
SAS_BLAD2_TX4_N (6) 
SAS_BLAD2_TX3_P (6) 
SAS_BLAD2_TX3_N (6) 
SAS_BLAD2_RX1_P (6) 
SAS_BLAD2_RX1_N (6) 
SAS_BLAD2_TX1_P (6) 
SAS_BLAD2_TX1_N (6) 
SAS_BLAD2_RX2_P (6) 
SAS_BLAD2_RX2_N (6) 
SAS_BLAD2_RX3_P (6) 
SAS_BLAD2_RX3_N (6) 
SAS_BLAD2_RX4_P (6) 
SAS_BLAD2_RX4_N (6) 
SAS_BLAD2_TX6_P (6) 
SAS_BLAD2_TX6_N (6) 
SAS_BLAD2_TX8_P (6) 
SAS_BLAD2_TX8_N (6) 
SAS_BLAD2_TX7_P (6) 
SAS_BLAD2_TX7_N (6) 
SAS_BLAD2_RX5_P (6) 
SAS_BLAD2_RX5_N (6) 
SAS_BLAD2_TX5_P (6) 
SAS_BLAD2_TX5_N (6) 
SAS_BLAD2_RX6_P (6) 
SAS_BLAD2_RX6_N (6) 
SAS_BLAD2_RX7_P (6) 
SAS_BLAD2_RX7_N (6) 
SAS_BLAD2_RX8_P (6) 
SAS_BLAD2_RX8_N (6) 
ENET1G_1_MDI1N (5) 
ENET1G_1_MDI2P (5) 
ENET1G_1_MDI2N (5) 
ENET1G_1_MDI3P (5) 
ENET1G_1_MDI3N (5) 
ENET1G_2_MDI2P (5) 
ENET1G_3_MDI2P (6) 
ENET1G_3_MDI2N (6) 
ENET1G_3_MDI1N (6) 
ENET1G_2_MDI1N (5) 
ENET1G_2_MDI2N (5) 
ENET1G_4_MDI2P (6) 
ENET1G_4_MDI2N (6) 
ENET1G_4_MDI1N (6) 
Title 
Size Document Number Rev
Date: Sheet 
of 
RJ45 & Mini SAS Connector 1A
Tray Backplane Assembly V1 
Cloud Server Infrastructure Engineering
C
7 11Monday, January 27, 2014 
Title 
Size Document Number Rev
Date: Sheet 
of 
RJ45 & Mini SAS Connector 1A
Tray Backplane Assembly V1 
Cloud Server Infrastructure Engineering
C
7 11Monday, January 27, 2014 
Title 
Size Document Number Rev
Date: Sheet 
of 
RJ45 & Mini SAS Connector 1A
Tray Backplane Assembly V1 
Cloud Server Infrastructure Engineering
C
7 11Monday, January 27, 2014 
J22A 
RJ45X2 
A1 
A2 
A3 
A4 
A5 
A6 
A7 
A8 
G1 
G2 
G3 
G4 
G5 
G6 
U3 
MINI_SAS_CON 
RX0P A2 
RX0N A3 
RX1P A5 
RX1N A6 
RX2P A8 
RX2N A9 
RX3P A11 
RX3N A12 
TX0P B2 
TX0N B3 
TX1P B5 
TX1N B6 
TX2P B8 
TX2N B9 
TX3P B11 
TX3N B12 
GND1 A1 
GND2 A4 
GND3 A7 
GND4 A10 
GND5 A13 
GND6 B1 
GND7 B4 
GND8 B7 
GND9 B10 
GND10 B13 
U2 
MINI_SAS_CON 
RX0P A2 
RX0N A3 
RX1P A5 
RX1N A6 
RX2P A8 
RX2N A9 
RX3P A11 
RX3N A12 
TX0P B2 
TX0N B3 
TX1P B5 
TX1N B6 
TX2P B8 
TX2N B9 
TX3P B11 
TX3N B12 
GND1 A1 
GND2 A4 
GND3 A7 
GND4 A10 
GND5 A13 
GND6 B1 
GND7 B4 
GND8 B7 
GND9 B10 
GND10 B13 
J23B 
RJ45X2 
B1 
B2 
B3 
B4 
B5 
B6 
B7 
B8 
J23A 
RJ45X2 
A1 
A2 
A3 
A4 
A5 
A6 
A7 
A8 
G1 
G2 
G3 
G4 
G5 
G6 
U4 
MINI_SAS_CON 
RX0P A2 
RX0N A3 
RX1P A5 
RX1N A6 
RX2P A8 
RX2N A9 
RX3P A11 
RX3N A12 
TX0P B2 
TX0N B3 
TX1P B5 
TX1N B6 
TX2P B8 
TX2N B9 
TX3P B11 
TX3N B12 
GND1 A1 
GND2 A4 
GND3 A7 
GND4 A10 
GND5 A13 
GND6 B1 
GND7 B4 
GND8 B7 
GND9 B10 
GND10 B13 
U1 
MINI_SAS_CON 
RX0P A2 
RX0N A3 
RX1P A5 
RX1N A6 
RX2P A8 
RX2N A9 
RX3P A11 
RX3N A12 
TX0P B2 
TX0N B3 
TX1P B5 
TX1N B6 
TX2P B8 
TX2N B9 
TX3P B11 
TX3N B12 
GND1 A1 
GND2 A4 
GND3 A7 
GND4 A10 
GND5 A13 
GND6 B1 
GND7 B4 
GND8 B7 
GND9 B10 
GND10 B13 
J22B 
RJ45X2 
B1 
B2 
B3 
B4 
B5 
B6 
B7 
B8 
U9 
MINI_SAS_CAGE 
GND4 B1 
GND3 A3 
GND1 A1 
GND2 A2 
GND8 B3 
GND5 B2 
G4 G4 
G5 G5 
G6 G6 
G1 G1 
G2 G2 
G3 G3 
U10 
MINI_SAS_CAGE 
GND4 B1 
GND3 A3 
GND1 A1 
GND2 A2 
GND8 B3 
GND5 B2 
G4 G4 
G5 G5 
G6 G6 
G1 G1 
G2 G2 
G3 G3 



5
5
4
4
3
3
2
2
1
1
D D
C C
B B
A A
SFP+ CONNECTOR - BLADE1 
DIRECT TOUCH CABLE ONLY DIRECT TOUCH CABLE ONLY 
ENET10G_1_TX_FAULT 
ENET10G_1_TX_DIS 
ENET10G_1_RS0 
ENET10G_1_TX_FAULT 
ENET10G_1_TX_DIS 
ENET10G_1_SDA 
ENET10G_1_SCL 
ENET10G_1_MOD_DEF0 
ENET10G_1_RS0 
ENET10G_1_LOS 
P3V3_10G_1_VCCT_L P3V3_10G_1_VCCT 
P3V3_10G_1_VCCT 
P3V3_10G_1_VCCR 
P3V3_10G_1_VCCR_L P3V3_10G_1_VCCR 
P3V3_10G_2_VCCR 
ENET10G_2_TX_FAULT 
P3V3_10G_2_VCCR_L P3V3_10G_2_VCCR 
ENET10G_2_TX_DIS 
P3V3_10G_2_VCCT_L 
ENET10G_2_RS0 
ENET10G_2_TX_FAULT 
ENET10G_2_TX_DIS 
ENET10G_2_SDA 
ENET10G_2_SCL 
ENET10G_2_MOD_DEF0 
ENET10G_2_RS0 
ENET10G_2_LOS 
P3V3_10G_2_VCCT 
P3V3_10G_2_VCCT 
ENET10G_2_RS1 ENET10G_1_RS1 
ENET10G_1_RS1 ENET10G_2_RS1 
ENET10G_1_TX_FAULT 
ENET10G_1_TX_DIS 
ENET10G_1_RS0 
ENET10G_1_RS1 
ENET10G_2_TX_FAULT 
ENET10G_2_TX_DIS 
ENET10G_2_RS0 
ENET10G_2_RS1 
ENET10G_1_TDN (5) 
ENET10G_1_TDP (5) 
ENET10G_1_RDP (5) 
ENET10G_1_RDN (5) 
ENET10G_2_TDN (5) 
ENET10G_2_TDP (5) 
ENET10G_2_RDP (5) 
ENET10G_2_RDN (5) 
ENET10G_1_MOD_DEF0 (5) 
ENET10G_1_LOS (5) 
ENET10G_2_MOD_DEF0 (5) 
ENET10G_2_LOS (5) 
ENET10G_1_SDA (5) 
ENET10G_1_SCL (5) 
ENET10G_2_SDA (5) 
ENET10G_2_SCL (5) 
P3V3_BLAD1 
P3V3_BLAD1 
P3V3_BLAD1 
P3V3_BLAD1 
P3V3_BLAD1 
P3V3_BLAD1 
Title 
Size Document Number Rev
Date: Sheet 
of 
10G Connector 1 1A
Tray Backplane Assembly V1 
Cloud Server Infrastructure Engineering
C
8 11Monday, January 27, 2014 
Title 
Size Document Number Rev
Date: Sheet 
of 
10G Connector 1 1A
Tray Backplane Assembly V1 
Cloud Server Infrastructure Engineering
C
8 11Monday, January 27, 2014 
Title 
Size Document Number Rev
Date: Sheet 
of 
10G Connector 1 1A
Tray Backplane Assembly V1 
Cloud Server Infrastructure Engineering
C
8 11Monday, January 27, 2014 
R14 10K 
5% R0402 
R13 10K 
5% R0402 
R46 100 NI 
U5 
SFP CONNECTOR 
VeeT 1
Tx_Fault 2
Tx_Disable 3
MOD-DEF2 4
MOD-DEF1 5
MOD-DEF0 6
Rate_Select0 7
LOS 8
VeeR 10 
VeeT 20 
TD- 19 
TD+ 18 
VeeT 17 
VccT 16 
RD+ 13 
RD- 12 
VccR 15 
VeeR 14 
VeeR 11 
Rate_Select1 9
R7 10K 
5% R0402 
NI 
R3 10K 
5% R0402 
L2 
BLM21PG331SN1D 
NI 21
L3 
BLM21PG331SN1D 
NI 21
R41 100 NI 
R40 100 NI 
SFP_CONN 
J15 
SFP+ Cage 
1 1
2 2
3 3
4 4
5 5
6 6
7 7
8 8
9 9
10 10 
11 11 
12 12 
13 13 
14 14 
15 15 
16 16 
17 17 
18 18 
19 19 
20 20 
R47 100 NI 
R79 0
C21 
0.1UF 
25V 
C0402 
FS1 
1.1A/6V 
NI 
1 2
R6 10K 
5% R0402 
NI 
C20 
100PF 
50V 
C0402 
C18 
100PF 
50V 
C0402 
R43 100 NI 
R45 100 NI 
R12 10K 
5% R0402 
L4 
BLM21PG331SN1D 
NI 21
R5 10K 
5% R0402 
NI 
FS2 
1.1A/6V 
NI 
1 2
R15 10K 
5% R0402 
R76 0
R11 10K 
5% R0402 
C23 
0.1UF 
25V 
C0402 
R2 10K 
5% R0402 
R77 0
C22 
100PF 
50V 
C0402 
R4 10K 
5% R0402 
R16 10K 
5% R0402 
L1 
BLM21PG331SN1D 
NI 21
C17 
0.1UF 
25V 
C0402 
SFP_CONN 
J16 
SFP+ Cage 
1 1
2 2
3 3
4 4
5 5
6 6
7 7
8 8
9 9
10 10 
11 11 
12 12 
13 13 
14 14 
15 15 
16 16 
17 17 
18 18 
19 19 
20 20 
U6 
SFP CONNECTOR 
VeeT 1
Tx_Fault 2
Tx_Disable 3
MOD-DEF2 4
MOD-DEF1 5
MOD-DEF0 6
Rate_Select0 7
LOS 8
VeeR 10 
VeeT 20 
TD- 19 
TD+ 18 
VeeT 17 
VccT 16 
RD+ 13 
RD- 12 
VccR 15 
VeeR 14 
VeeR 11 
Rate_Select1 9
C24 
100PF 
50V 
C0402 
R42 100 NI 
R1 10K 
5% R0402 
R10 10K 
5% R0402 
R44 100 NI 
R8 10K 
5% R0402 
NI 
FS3 
1.1A/6V 
NI 
1 2
C19 
0.1UF 
25V 
C0402 
FS4 
1.1A/6V 
NI 
1 2
R9 10K 
5% R0402 
R78 0



5
5
4
4
3
3
2
2
1
1
D D
C C
B B
A A
SFP+ CONNECTOR - BLADE2 
DIRECT TOUCH CABLE ONLY DIRECT TOUCH CABLE ONLY 
ENET10G_3_RS1 
P3V3_10G_3_VCCR 
ENET10G_4_RS1 
ENET10G_3_TX_FAULT 
P3V3_10G_3_VCCR_L P3V3_10G_3_VCCR 
ENET10G_3_TX_DIS 
P3V3_10G_3_VCCT_L 
ENET10G_3_RS0 
ENET10G_3_TX_FAULT 
ENET10G_3_TX_DIS 
ENET10G_3_SDA 
ENET10G_3_SCL 
ENET10G_3_MOD_DEF0 
ENET10G_3_RS0 
ENET10G_3_LOS 
P3V3_10G_4_VCCR 
ENET10G_4_TX_FAULT 
P3V3_10G_4_VCCR_L P3V3_10G_4_VCCR 
ENET10G_4_TX_DIS 
P3V3_10G_4_VCCT_L 
ENET10G_4_RS0 
ENET10G_4_TX_FAULT 
ENET10G_4_TX_DIS 
ENET10G_4_SDA 
ENET10G_4_SCL 
ENET10G_4_MOD_DEF0 
ENET10G_4_RS0 
ENET10G_4_LOS 
P3V3_10G_4_VCCT 
P3V3_10G_4_VCCT 
ENET10G_4_RS1 
P3V3_10G_3_VCCT 
P3V3_10G_3_VCCT 
ENET10G_3_RS1 
ENET10G_3_TX_FAULT 
ENET10G_3_TX_DIS 
ENET10G_3_RS0 
ENET10G_3_RS1 
ENET10G_4_TX_FAULT 
ENET10G_4_TX_DIS 
ENET10G_4_RS0 
ENET10G_4_RS1 
ENET10G_3_TDN (6) 
ENET10G_3_TDP (6) 
ENET10G_4_TDN (6) 
ENET10G_4_TDP (6) 
ENET10G_4_RDP (6) 
ENET10G_4_RDN (6) 
ENET10G_3_RDP (6) 
ENET10G_3_RDN (6) 
ENET10G_3_MOD_DEF0 (6) 
ENET10G_3_LOS (6) 
ENET10G_4_MOD_DEF0 (6) 
ENET10G_4_LOS (6) 
ENET10G_3_SDA (6) 
ENET10G_3_SCL (6) 
ENET10G_4_SDA (6) 
ENET10G_4_SCL (6) 
P3V3_BLAD2 
P3V3_BLAD2 
P3V3_BLAD2 
P3V3_BLAD2 
P3V3_BLAD2 
P3V3_BLAD2 
Title 
Size Document Number Rev
Date: Sheet 
of 
10G Connector 2 1A
Tray Backplane Assembly V1 
Cloud Server Infrastructure Engineering
C
9 11Monday, January 27, 2014 
Title 
Size Document Number Rev
Date: Sheet 
of 
10G Connector 2 1A
Tray Backplane Assembly V1 
Cloud Server Infrastructure Engineering
C
9 11Monday, January 27, 2014 
Title 
Size Document Number Rev
Date: Sheet 
of 
10G Connector 2 1A
Tray Backplane Assembly V1 
Cloud Server Infrastructure Engineering
C
9 11Monday, January 27, 2014 
L8 
BLM21PG331SN1D 
NI 21
R23 10K 
5% R0402 
NI 
C30 
100PF 
50V 
C0402 
R54 100 NI 
R25 10K 
5% R0402 
C29 
0.1UF 
25V 
C0402 
R20 10K 
5% R0402 
C32 
100PF 
50V 
C0402 
R31 10K 
5% R0402 
R26 10K 
5% R0402 
R18 10K 
5% R0402 
R83 0
C27 
0.1UF 
25V 
C0402 
R29 10K 
5% R0402 
R24 10K 
5% R0402 
NI 
R50 100 NI 
U8 
SFP CONNECTOR 
VeeT 1
Tx_Fault 2
Tx_Disable 3
MOD-DEF2 4
MOD-DEF1 5
MOD-DEF0 6
Rate_Select0 7
LOS 8
VeeR 10 
VeeT 20 
TD- 19 
TD+ 18 
VeeT 17 
VccT 16 
RD+ 13 
RD- 12 
VccR 15 
VeeR 14 
VeeR 11 
Rate_Select1 9
FS7 
1.1A/6V 
NI 
1 2
R32 10K 
5% R0402 
R19 10K 
5% R0402 C25 
0.1UF 
25V 
C0402 
R21 10K 
5% R0402 
NI 
R53 100 NI 
C31 
0.1UF 
25V 
C0402 
FS5 
1.1A/6V 
NI 
1 2
R49 100 NI 
R52 100 NI 
U7 
SFP CONNECTOR 
VeeT 1
Tx_Fault 2
Tx_Disable 3
MOD-DEF2 4
MOD-DEF1 5
MOD-DEF0 6
Rate_Select0 7
LOS 8
VeeR 10 
VeeT 20 
TD- 19 
TD+ 18 
VeeT 17 
VccT 16 
RD+ 13 
RD- 12 
VccR 15 
VeeR 14 
VeeR 11 
Rate_Select1 9
R55 100 NI 
L5 
BLM21PG331SN1D 
NI 21
FS6 
1.1A/6V 
NI 
1 2
L6 
BLM21PG331SN1D 
NI 21
R48 100 NI 
FS8 
1.1A/6V 
NI 
1 2
C28 
100PF 
50V 
C0402 
R27 10K 
5% R0402 
R22 10K 
5% R0402 
NI 
R80 0 R82 0
R28 10K 
5% R0402 
R17 10K 
5% R0402 
C26 
100PF 
50V 
C0402 
SFP_CONN 
J18 
SFP+ Cage 
1 1
2 2
3 3
4 4
5 5
6 6
7 7
8 8
9 9
10 10 
11 11 
12 12 
13 13 
14 14 
15 15 
16 16 
17 17 
18 18 
19 19 
20 20 
R30 10K 
5% R0402 
SFP_CONN 
J17 
SFP+ Cage 
1 1
2 2
3 3
4 4
5 5
6 6
7 7
8 8
9 9
10 10 
11 11 
12 12 
13 13 
14 14 
15 15 
16 16 
17 17 
18 18 
19 19 
20 20 
R81 0
R51 100 NI 
L7 
BLM21PG331SN1D 
NI 21



5
5
4
4
3
3
2
2
1
1
D D
C C
B B
A A
Gold finger 
FOR MFG AND DEBUG 
FOR DEBUG 
FOR DEBUG 
PS_EN_PSU_N 
NODE1_RXD (5) 
NODE1_TXD (5) 
NODE1_EN (5) 
NODE2_EN (5) 
NODE2_RXD (5) 
NODE2_TXD (5) 
NODE3_RXD (6) 
NODE3_TXD (6) 
NODE3_EN (6) 
NODE4_EN (6) 
NODE4_RXD (6) 
NODE4_TXD (6) 
P12V P12V 
P12V 
Title 
Size Document Number Rev
Date: Sheet 
of 
Golden Finger 1A
Tray Backplane Assembly V1 
Cloud Server Infrastructure Engineering
C
10 11Monday, January 27, 2014 
Title 
Size Document Number Rev
Date: Sheet 
of 
Golden Finger 1A
Tray Backplane Assembly V1 
Cloud Server Infrastructure Engineering
C
10 11Monday, January 27, 2014 
Title 
Size Document Number Rev
Date: Sheet 
of 
Golden Finger 1A
Tray Backplane Assembly V1 
Cloud Server Infrastructure Engineering
C
10 11Monday, January 27, 2014 
R33 100 
R0402 5% 
J21 
HEADER2X6 
NI 
1 2
3 4
5 6
7
9
8
10 
11 12 
Signal 
SEG1 
SEG2 
SEG3 
SEG4 SEG5 
SEG6 
SEG7 
SEG8 
GOLD FINGER 
J19 
GOLD44_10117936003LF 
S3 S3 
S4 S4 
S5 S5 
S6 S6 
S12 S12 
S11 S11 
S10 S10 
S9 S9 
S8 S8 
S7 S7 
P1 P1 
P2 P2 
P3 P3 
S2 S2 S1 S1 
P4 P4 P5 P5 
P6 P6 
P7 P7 
P8 P8 
J20 
PWR_CON_2X9 
NI 
1
2
3
4
5
6
7
8
9
10 
11 
12 
13 
14 
15 
16 
17 
18 



5
5
4
4
3
3
2
2
1
1
D D
C C
B B
A A
2.6 x 4.8 2.6 x 10.8 
Title 
Size Document Number Rev
Date: Sheet 
of 
Screw Hole 1A
Tray Backplane Assembly V1 
Cloud Server Infrastructure Engineering
C
11 11Monday, January 27, 2014 
Title 
Size Document Number Rev
Date: Sheet 
of 
Screw Hole 1A
Tray Backplane Assembly V1 
Cloud Server Infrastructure Engineering
C
11 11Monday, January 27, 2014 
Title 
Size Document Number Rev
Date: Sheet 
of 
Screw Hole 1A
Tray Backplane Assembly V1 
Cloud Server Infrastructure Engineering
C
11 11Monday, January 27, 2014 
H1 
HOLE_C8D3-5_6B8_OB6XC3N 
GNDPAD2 
GNDPAD_SMD103X426T 
1
GNDPAD1 
GNDPAD_SMD103X189T 
1
H6 
HOLE_C8D3-5_6B8_OB6XC3N 
H3 
HOLE_C8D3-5_6B8_OB6XC3N 
H2 
HOLE_C8D3-5_6B8_OB6XC3N 
H8 
GNDHOLE_8PIN 
H5 
HOLE_C8D3-5_6B8_OB6XC3N 
H4 
HOLE_C8D3-5_6B8_OB6XC3N 
H7 
GNDHOLE_8PIN 